# T6G (Grand Teton) — schematic netlist excerpt (pin names and nets, part order shuffled) for the footprints in the layout excerpt that follows; sources: Cadence DE-HDL packaged netlist, KiCad conversion of 04192023_DAF0TMB3IC0_F0TG_MB_C_brd_V02_OCP.brd

R6305  Q_RES  0 5% CHIP  pkg 0402LF  page 179 : A = USB_HUB2_MRP_CFG_NON_REM ; B = USB_HUB2_TI_HS_SUSPEND_MRP_CFG_NON_REM
PR262  Q_RES  8.87K 1% EMPTY  pkg 0402LF  page 219 : A = PVDDCR_CPU1_P1_LSET4 ; B = GND
R671  Q_RES  49.9 1% CHIP  pkg 0201LF  page 331 : A = SMB_RT_CPU1_P1_ROM_MUX_1D_SDA ; B = SMB_RT_CPU1_P1_ROM_MUX_1D_R_SDA

(kicad_pcb
	(version 20260206)
	(generator "pcbnew")
	(generator_version "10.0")
	(general
		(thickness 1.6)
		(legacy_teardrops no)
	)
	(paper "A4")
	(title_block
		(title "04192023_DAF0TMB3IC0_F0TG_MB_C_brd_V02_OCP.brd")
		(comment 1 "Grand Teton / footprints 4168-4170 of 8354")
	)
	(layers
		(0 "F.Cu" signal "TOP")
		(4 "In1.Cu" signal "GND")
		(6 "In2.Cu" signal "IN1")
		(8 "In3.Cu" signal "GND1")
		(10 "In4.Cu" signal "IN2")
		(12 "In5.Cu" signal "GND2")
		(14 "In6.Cu" signal "IN3")
		(16 "In7.Cu" signal "GND3")
		(18 "In8.Cu" signal "VCC")
		(20 "In9.Cu" signal "VCC1")
		(22 "In10.Cu" signal "GND4")
		(24 "In11.Cu" signal "IN4")
		(26 "In12.Cu" signal "GND5")
		(28 "In13.Cu" signal "IN5")
		(30 "In14.Cu" signal "GND6")
		(32 "In15.Cu" signal "IN6")
		(34 "In16.Cu" signal "GND7")
		(2 "B.Cu" signal "BOTTOM")
		(9 "F.Adhes" user "F.Adhesive")
		(11 "B.Adhes" user "B.Adhesive")
		(13 "F.Paste" user "Package Geometry/Pastemask Top")
		(15 "B.Paste" user "Package Geometry/Pastemask Bottom")
		(5 "F.SilkS" user "Ref Des/Silkscreen Top")
		(7 "B.SilkS" user "Ref Des/Silkscreen Bottom")
		(1 "F.Mask" user "Board Geometry/Soldermask Top")
		(3 "B.Mask" user "Board Geometry/Soldermask Bottom")
		(17 "Dwgs.User" user "User.Drawings")
		(19 "Cmts.User" user "User.Comments")
		(21 "Eco1.User" user "User.Eco1")
		(23 "Eco2.User" user "User.Eco2")
		(25 "Edge.Cuts" user "Board Geometry/Outline")
		(27 "Margin" user)
		(31 "F.CrtYd" user "Package Geometry/Place Bound Top")
		(29 "B.CrtYd" user "Package Geometry/Place Bound Bottom")
		(35 "F.Fab" user "Ref Des/Assembly Top")
		(33 "B.Fab" user "Ref Des/Assembly Bottom")
	)
	(footprint ""
		(layer "F.Cu")
		(at 111.581946 -52.86248 -90)
		(property "Reference" "R6305"
			(at 0 0 270)
			(layer "F.SilkS")
			(hide yes)
			(effects
				(font
					(size 1.27 1.27)
				)
			)
		)
		(property "Value" ""
			(at 0 0 270)
			(layer "F.Fab")
			(effects
				(font
					(size 1.27 1.27)
				)
			)
		)
		(duplicate_pad_numbers_are_jumpers no)
		(fp_line
			(start -0.7874 0.4064)
			(end -0.7874 -0.4064)
			(stroke
				(width 0.1524)
				(type default)
			)
			(layer "F.SilkS")
		)
		(fp_line
			(start 0.7874 0.4064)
			(end -0.7874 0.4064)
			(stroke
				(width 0.1524)
				(type default)
			)
			(layer "F.SilkS")
		)
		(fp_line
			(start -0.7874 -0.4064)
			(end 0.7874 -0.4064)
			(stroke
				(width 0.1524)
				(type default)
			)
			(layer "F.SilkS")
		)
		(fp_line
			(start 0.7874 -0.4064)
			(end 0.7874 0.4064)
			(stroke
				(width 0.1524)
				(type default)
			)
			(layer "F.SilkS")
		)
		(fp_line
			(start -0.67945 0.3048)
			(end -0.67945 -0.305054)
			(stroke
				(width 0.1)
				(type default)
			)
			(layer "F.Fab")
		)
		(fp_line
			(start -0.12065 0.3048)
			(end -0.67945 0.3048)
			(stroke
				(width 0.1)
				(type default)
			)
			(layer "F.Fab")
		)
		(fp_line
			(start 0.120396 0.3048)
			(end 0.120396 0.2794)
			(stroke
				(width 0.1)
				(type default)
			)
			(layer "F.Fab")
		)
		(fp_line
			(start 0.67945 0.3048)
			(end 0.120396 0.3048)
			(stroke
				(width 0.1)
				(type default)
			)
			(layer "F.Fab")
		)
		(fp_line
			(start -0.12065 0.2794)
			(end -0.12065 0.3048)
			(stroke
				(width 0.1)
				(type default)
			)
			(layer "F.Fab")
		)
		(fp_line
			(start 0.120396 0.2794)
			(end -0.12065 0.2794)
			(stroke
				(width 0.1)
				(type default)
			)
			(layer "F.Fab")
		)
		(fp_line
			(start -0.12065 -0.2794)
			(end 0.12065 -0.2794)
			(stroke
				(width 0.1)
				(type default)
			)
			(layer "F.Fab")
		)
		(fp_line
			(start 0.12065 -0.2794)
			(end 0.12065 -0.3048)
			(stroke
				(width 0.1)
				(type default)
			)
			(layer "F.Fab")
		)
		(fp_line
			(start 0.12065 -0.3048)
			(end 0.67945 -0.3048)
			(stroke
				(width 0.1)
				(type default)
			)
			(layer "F.Fab")
		)
		(fp_line
			(start 0.67945 -0.3048)
			(end 0.67945 0.3048)
			(stroke
				(width 0.1)
				(type default)
			)
			(layer "F.Fab")
		)
		(fp_line
			(start -0.67945 -0.305054)
			(end -0.12065 -0.305054)
			(stroke
				(width 0.1)
				(type default)
			)
			(layer "F.Fab")
		)
		(fp_line
			(start -0.12065 -0.305054)
			(end -0.12065 -0.2794)
			(stroke
				(width 0.1)
				(type default)
			)
			(layer "F.Fab")
		)
		(pad "1" smd circle
			(at -0.40005 0 270)
			(size 0 0)
			(layers "F.Cu" "F.Mask" "F.Paste")
			(net "USB_HUB2_MRP_CFG_NON_REM")
		)
		(pad "2" smd circle
			(at 0.40005 0 270)
			(size 0 0)
			(layers "F.Cu" "F.Mask" "F.Paste")
			(net "USB_HUB2_TI_HS_SUSPEND_MRP_CFG_NON_REM")
		)
	)
	(footprint ""
		(layer "F.Cu")
		(at 60.57011 -351.932748)
		(property "Reference" "PR262"
			(at 0 0 0)
			(layer "F.SilkS")
			(hide yes)
			(effects
				(font
					(size 1.27 1.27)
				)
			)
		)
		(property "Value" ""
			(at 0 0 0)
			(layer "F.Fab")
			(effects
				(font
					(size 1.27 1.27)
				)
			)
		)
		(duplicate_pad_numbers_are_jumpers no)
		(fp_line
			(start -0.7874 -0.4064)
			(end 0.7874 -0.4064)
			(stroke
				(width 0.1524)
				(type default)
			)
			(layer "F.SilkS")
		)
		(fp_line
			(start -0.7874 0.4064)
			(end -0.7874 -0.4064)
			(stroke
				(width 0.1524)
				(type default)
			)
			(layer "F.SilkS")
		)
		(fp_line
			(start 0.7874 -0.4064)
			(end 0.7874 0.4064)
			(stroke
				(width 0.1524)
				(type default)
			)
			(layer "F.SilkS")
		)
		(fp_line
			(start 0.7874 0.4064)
			(end -0.7874 0.4064)
			(stroke
				(width 0.1524)
				(type default)
			)
			(layer "F.SilkS")
		)
		(fp_line
			(start -0.67945 -0.305054)
			(end -0.12065 -0.305054)
			(stroke
				(width 0.1)
				(type default)
			)
			(layer "F.Fab")
		)
		(fp_line
			(start -0.67945 0.3048)
			(end -0.67945 -0.305054)
			(stroke
				(width 0.1)
				(type default)
			)
			(layer "F.Fab")
		)
		(fp_line
			(start -0.12065 -0.305054)
			(end -0.12065 -0.2794)
			(stroke
				(width 0.1)
				(type default)
			)
			(layer "F.Fab")
		)
		(fp_line
			(start -0.12065 -0.2794)
			(end 0.12065 -0.2794)
			(stroke
				(width 0.1)
				(type default)
			)
			(layer "F.Fab")
		)
		(fp_line
			(start -0.12065 0.2794)
			(end -0.12065 0.3048)
			(stroke
				(width 0.1)
				(type default)
			)
			(layer "F.Fab")
		)
		(fp_line
			(start -0.12065 0.3048)
			(end -0.67945 0.3048)
			(stroke
				(width 0.1)
				(type default)
			)
			(layer "F.Fab")
		)
		(fp_line
			(start 0.120396 0.2794)
			(end -0.12065 0.2794)
			(stroke
				(width 0.1)
				(type default)
			)
			(layer "F.Fab")
		)
		(fp_line
			(start 0.120396 0.3048)
			(end 0.120396 0.2794)
			(stroke
				(width 0.1)
				(type default)
			)
			(layer "F.Fab")
		)
		(fp_line
			(start 0.12065 -0.3048)
			(end 0.67945 -0.3048)
			(stroke
				(width 0.1)
				(type default)
			)
			(layer "F.Fab")
		)
		(fp_line
			(start 0.12065 -0.2794)
			(end 0.12065 -0.3048)
			(stroke
				(width 0.1)
				(type default)
			)
			(layer "F.Fab")
		)
		(fp_line
			(start 0.67945 -0.3048)
			(end 0.67945 0.3048)
			(stroke
				(width 0.1)
				(type default)
			)
			(layer "F.Fab")
		)
		(fp_line
			(start 0.67945 0.3048)
			(end 0.120396 0.3048)
			(stroke
				(width 0.1)
				(type default)
			)
			(layer "F.Fab")
		)
		(pad "1" smd circle
			(at -0.40005 0)
			(size 0 0)
			(layers "F.Cu" "F.Mask" "F.Paste")
			(net "PVDDCR_CPU1_P1_LSET4")
		)
		(pad "2" smd circle
			(at 0.40005 0)
			(size 0 0)
			(layers "F.Cu" "F.Mask" "F.Paste")
			(net "GND")
		)
	)
	(footprint ""
		(layer "F.Cu")
		(at 104.47528 -394.7668 -90)
		(property "Reference" "R671"
			(at 0 0 270)
			(layer "F.SilkS")
			(hide yes)
			(effects
				(font
					(size 1.27 1.27)
				)
			)
		)
		(property "Value" ""
			(at 0 0 270)
			(layer "F.Fab")
			(effects
				(font
					(size 1.27 1.27)
				)
			)
		)
		(duplicate_pad_numbers_are_jumpers no)
		(fp_line
			(start -0.32512 0.175006)
			(end -0.32512 -0.175006)
			(stroke
				(width 0.1)
				(type default)
			)
			(layer "F.Fab")
		)
		(fp_line
			(start 0.32512 0.175006)
			(end -0.32512 0.175006)
			(stroke
				(width 0.1)
				(type default)
			)
			(layer "F.Fab")
		)
		(fp_line
			(start -0.32512 -0.175006)
			(end 0.32512 -0.175006)
			(stroke
				(width 0.1)
				(type default)
			)
			(layer "F.Fab")
		)
		(fp_line
			(start 0.32512 -0.175006)
			(end 0.32512 0.175006)
			(stroke
				(width 0.1)
				(type default)
			)
			(layer "F.Fab")
		)
		(pad "1" smd rect
			(at -0.2667 0 270)
			(size 0.3048 0.381)
			(layers "F.Cu" "F.Mask" "F.Paste")
			(net "SMB_RT_CPU1_P1_ROM_MUX_1D_SDA")
		)
		(pad "2" smd rect
			(at 0.2667 0 90)
			(size 0.3048 0.381)
			(layers "F.Cu" "F.Mask" "F.Paste")
			(net "SMB_RT_CPU1_P1_ROM_MUX_1D_R_SDA")
		)
	)
)
